# BASEBOARD_FAB2 (Tioga Pass) — schematic netlist excerpt (pin names and nets, part order shuffled) for the footprints in the layout excerpt that follows; sources: Cadence DE-HDL packaged netlist, KiCad conversion of Wiwynn_Tioga_Pass_MB.brd

R1D51  RES  10.0 1% CHIP  pkg 0402  page 200 : A = A_HSC_C ; B = A_HSC_GATE
C3A7  CAP  10UF 4V 20% X6S  pkg 0603LF  page 234 : A = PVPP_KLM ; B = GND
R1C31  RES  0.0 5% EMPTY  pkg 0402  page 182 : A = FM_XRC_READY_N ; B = FAN_TACH0_R

(kicad_pcb
	(version 20260206)
	(generator "pcbnew")
	(generator_version "10.0")
	(general
		(thickness 1.6)
		(legacy_teardrops no)
	)
	(paper "A4")
	(title_block
		(title "Wiwynn_Tioga_Pass_MB.brd")
		(comment 1 "Tioga Pass / footprints 266-268 of 4770")
	)
	(layers
		(0 "F.Cu" signal "TOP")
		(4 "In1.Cu" signal "L2GND")
		(6 "In2.Cu" signal "L3")
		(8 "In3.Cu" signal "L4GND")
		(10 "In4.Cu" signal "L5")
		(12 "In5.Cu" signal "L6GND")
		(14 "In6.Cu" signal "L7VCC")
		(16 "In7.Cu" signal "L8VCC")
		(18 "In8.Cu" signal "L9GND")
		(20 "In9.Cu" signal "L10")
		(22 "In10.Cu" signal "L11GND")
		(24 "In11.Cu" signal "L12")
		(26 "In12.Cu" signal "L13GND")
		(2 "B.Cu" signal "BOTTOM")
		(9 "F.Adhes" user "F.Adhesive")
		(11 "B.Adhes" user "B.Adhesive")
		(13 "F.Paste" user "Package Geometry/Pastemask Top")
		(15 "B.Paste" user "Package Geometry/Pastemask Bottom")
		(5 "F.SilkS" user "Ref Des/Silkscreen Top")
		(7 "B.SilkS" user "Ref Des/Silkscreen Bottom")
		(1 "F.Mask" user "Board Geometry/Soldermask Top")
		(3 "B.Mask" user "Board Geometry/Soldermask Bottom")
		(17 "Dwgs.User" user "User.Drawings")
		(19 "Cmts.User" user "User.Comments")
		(21 "Eco1.User" user "User.Eco1")
		(23 "Eco2.User" user "User.Eco2")
		(25 "Edge.Cuts" user "Board Geometry/Outline")
		(27 "Margin" user)
		(31 "F.CrtYd" user "Package Geometry/Place Bound Top")
		(29 "B.CrtYd" user "Package Geometry/Place Bound Bottom")
		(35 "F.Fab" user "Ref Des/Assembly Top")
		(33 "B.Fab" user "Ref Des/Assembly Bottom")
	)
	(footprint ""
		(layer "F.Cu")
		(at 153.4922 -140.0048 -90)
		(property "Reference" "C3A7"
			(at 0 0 270)
			(layer "F.SilkS")
			(hide yes)
			(effects
				(font
					(size 1.27 1.27)
				)
			)
		)
		(property "Value" ""
			(at 0 0 270)
			(layer "F.Fab")
			(effects
				(font
					(size 1.27 1.27)
				)
			)
		)
		(duplicate_pad_numbers_are_jumpers no)
		(fp_rect
			(start -0.4953 1.6002)
			(end 0.4953 -0.2032)
			(stroke
				(width 0)
				(type default)
			)
			(fill no)
			(layer "F.CrtYd")
		)
		(fp_line
			(start -0.4953 1.6002)
			(end -0.4953 -0.2032)
			(stroke
				(width 0.1)
				(type default)
			)
			(layer "F.Fab")
		)
		(fp_line
			(start 0.4953 1.6002)
			(end -0.4953 1.6002)
			(stroke
				(width 0.1)
				(type default)
			)
			(layer "F.Fab")
		)
		(fp_line
			(start -0.4953 -0.2032)
			(end 0.4953 -0.2032)
			(stroke
				(width 0.1)
				(type default)
			)
			(layer "F.Fab")
		)
		(fp_line
			(start 0.4953 -0.2032)
			(end 0.4953 1.6002)
			(stroke
				(width 0.1)
				(type default)
			)
			(layer "F.Fab")
		)
		(pad "1" smd rect
			(at 0 0 270)
			(size 0.762 0.889)
			(layers "F.Cu" "F.Mask" "F.Paste")
			(net "PVPP_KLM")
		)
		(pad "2" smd rect
			(at 0 1.397 270)
			(size 0.762 0.889)
			(layers "F.Cu" "F.Mask" "F.Paste")
			(net "GND")
		)
		(zone
			(layer "F.Cu")
			(hatch none 0.5)
			(connect_pads
				(clearance 0)
			)
			(min_thickness 0.25)
			(keepout
				(tracks not_allowed)
				(vias allowed)
				(pads allowed)
				(copperpour not_allowed)
				(footprints allowed)
			)
			(placement
				(enabled no)
				(sheetname "")
			)
			(fill
				(thermal_gap 0.5)
				(thermal_bridge_width 0.5)
				(island_removal_mode 0)
			)
			(polygon
				(pts
					(xy 152.5397 -140.3858) (xy 152.5397 -139.6238) (xy 153.0477 -139.6238) (xy 153.0477 -140.3858)
				)
			)
		)
	)
	(footprint ""
		(layer "F.Cu")
		(at 12.446 -102.0064)
		(property "Reference" "R1C31"
			(at 0 0 0)
			(layer "F.SilkS")
			(hide yes)
			(effects
				(font
					(size 1.27 1.27)
				)
			)
		)
		(property "Value" ""
			(at 0 0 0)
			(layer "F.Fab")
			(effects
				(font
					(size 1.27 1.27)
				)
			)
		)
		(duplicate_pad_numbers_are_jumpers no)
		(fp_poly
			(pts
				(xy -0.2794 -0.1016) (xy 0.2794 -0.1016) (xy 0.2794 0.9906) (xy -0.2794 0.9906)
			)
			(stroke
				(width 0)
				(type default)
			)
			(fill no)
			(layer "F.CrtYd")
		)
		(fp_line
			(start -0.2794 -0.1016)
			(end -0.2794 0.9906)
			(stroke
				(width 0.1)
				(type default)
			)
			(layer "F.Fab")
		)
		(fp_line
			(start -0.2794 0.9906)
			(end 0.2794 0.9906)
			(stroke
				(width 0.1)
				(type default)
			)
			(layer "F.Fab")
		)
		(fp_line
			(start 0.2794 -0.1016)
			(end -0.2794 -0.1016)
			(stroke
				(width 0.1)
				(type default)
			)
			(layer "F.Fab")
		)
		(fp_line
			(start 0.2794 0.9906)
			(end 0.2794 -0.1016)
			(stroke
				(width 0.1)
				(type default)
			)
			(layer "F.Fab")
		)
		(pad "1" smd rect
			(at 0 0)
			(size 0.508 0.508)
			(layers "F.Cu" "F.Mask" "F.Paste")
			(net "FM_XRC_READY_N")
		)
		(pad "2" smd rect
			(at 0 0.889)
			(size 0.508 0.508)
			(layers "F.Cu" "F.Mask" "F.Paste")
			(net "FAN_TACH0_R")
		)
		(zone
			(layer "F.Cu")
			(hatch none 0.5)
			(connect_pads
				(clearance 0)
			)
			(min_thickness 0.25)
			(keepout
				(tracks allowed)
				(vias not_allowed)
				(pads allowed)
				(copperpour not_allowed)
				(footprints allowed)
			)
			(placement
				(enabled no)
				(sheetname "")
			)
			(fill
				(thermal_gap 0.5)
				(thermal_bridge_width 0.5)
				(island_removal_mode 0)
			)
			(polygon
				(pts
					(xy 12.192 -101.7524) (xy 12.7 -101.7524) (xy 12.7 -101.3714) (xy 12.192 -101.3714)
				)
			)
		)
		(zone
			(layer "F.Cu")
			(hatch none 0.5)
			(connect_pads
				(clearance 0)
			)
			(min_thickness 0.25)
			(keepout
				(tracks not_allowed)
				(vias allowed)
				(pads allowed)
				(copperpour not_allowed)
				(footprints allowed)
			)
			(placement
				(enabled no)
				(sheetname "")
			)
			(fill
				(thermal_gap 0.5)
				(thermal_bridge_width 0.5)
				(island_removal_mode 0)
			)
			(polygon
				(pts
					(xy 12.192 -101.3714) (xy 12.7 -101.3714) (xy 12.7 -101.7524) (xy 12.192 -101.7524)
				)
			)
		)
	)
	(footprint ""
		(layer "F.Cu")
		(at 26.2255 -66.46672 180)
		(property "Reference" "R1D51"
			(at 0 0 180)
			(layer "F.SilkS")
			(hide yes)
			(effects
				(font
					(size 1.27 1.27)
				)
			)
		)
		(property "Value" ""
			(at 0 0 180)
			(layer "F.Fab")
			(effects
				(font
					(size 1.27 1.27)
				)
			)
		)
		(duplicate_pad_numbers_are_jumpers no)
		(fp_poly
			(pts
				(xy -0.2794 -0.1016) (xy 0.2794 -0.1016) (xy 0.2794 0.9906) (xy -0.2794 0.9906)
			)
			(stroke
				(width 0)
				(type default)
			)
			(fill no)
			(layer "F.CrtYd")
		)
		(fp_line
			(start 0.2794 0.9906)
			(end 0.2794 -0.1016)
			(stroke
				(width 0.1)
				(type default)
			)
			(layer "F.Fab")
		)
		(fp_line
			(start 0.2794 -0.1016)
			(end -0.2794 -0.1016)
			(stroke
				(width 0.1)
				(type default)
			)
			(layer "F.Fab")
		)
		(fp_line
			(start -0.2794 0.9906)
			(end 0.2794 0.9906)
			(stroke
				(width 0.1)
				(type default)
			)
			(layer "F.Fab")
		)
		(fp_line
			(start -0.2794 -0.1016)
			(end -0.2794 0.9906)
			(stroke
				(width 0.1)
				(type default)
			)
			(layer "F.Fab")
		)
		(pad "1" smd rect
			(at 0 0 180)
			(size 0.508 0.508)
			(layers "F.Cu" "F.Mask" "F.Paste")
			(net "A_HSC_C")
		)
		(pad "2" smd rect
			(at 0 0.889 180)
			(size 0.508 0.508)
			(layers "F.Cu" "F.Mask" "F.Paste")
			(net "A_HSC_GATE")
		)
		(zone
			(layer "F.Cu")
			(hatch none 0.5)
			(connect_pads
				(clearance 0)
			)
			(min_thickness 0.25)
			(keepout
				(tracks not_allowed)
				(vias allowed)
				(pads allowed)
				(copperpour not_allowed)
				(footprints allowed)
			)
			(placement
				(enabled no)
				(sheetname "")
			)
			(fill
				(thermal_gap 0.5)
				(thermal_bridge_width 0.5)
				(island_removal_mode 0)
			)
			(polygon
				(pts
					(xy 26.4795 -67.10172) (xy 25.9715 -67.10172) (xy 25.9715 -66.72072) (xy 26.4795 -66.72072)
				)
			)
		)
		(zone
			(layer "F.Cu")
			(hatch none 0.5)
			(connect_pads
				(clearance 0)
			)
			(min_thickness 0.25)
			(keepout
				(tracks allowed)
				(vias not_allowed)
				(pads allowed)
				(copperpour not_allowed)
				(footprints allowed)
			)
			(placement
				(enabled no)
				(sheetname "")
			)
			(fill
				(thermal_gap 0.5)
				(thermal_bridge_width 0.5)
				(island_removal_mode 0)
			)
			(polygon
				(pts
					(xy 26.4795 -66.72072) (xy 25.9715 -66.72072) (xy 25.9715 -67.10172) (xy 26.4795 -67.10172)
				)
			)
		)
	)
)
